# S9S_MB_2U (Grand Teton) — schematic netlist excerpt (pin names and nets, part order shuffled) for the footprints in the layout excerpt that follows; sources: Cadence DE-HDL packaged netlist, KiCad conversion of 03242023_DA0F0TMBIJ0_F0T_Motherboard_J_brd_V01_OCP.brd

R2513  Q_RES  0 5% CHIP  pkg 0402LF  page 239 : A = PD_GTL2014_BMC_JTAG_DIR_2 ; B = GND
PR2528  Q_RES  10 1% EMPTY  pkg 0402LF  page 304 : A = P12V_HSC_GATE_G1 ; B = P12V_HSC_GATE2
PC1210  Q_CAPP  270UF 16V 20% OSCON  pkg THLF  page 290 : A = SW_P12V_PVCCFA_EHV_FIVRA_CPU1_R ; B = GND

(kicad_pcb
	(version 20260206)
	(generator "pcbnew")
	(generator_version "10.0")
	(general
		(thickness 1.6)
		(legacy_teardrops no)
	)
	(paper "A4")
	(title_block
		(title "03242023_DA0F0TMBIJ0_F0T_Motherboard_J_brd_V01_OCP.brd")
		(comment 1 "Grand Teton / footprints 3780-3782 of 6105")
	)
	(layers
		(0 "F.Cu" signal "TOP")
		(4 "In1.Cu" signal "GND")
		(6 "In2.Cu" signal "IN1")
		(8 "In3.Cu" signal "GND1")
		(10 "In4.Cu" signal "IN2")
		(12 "In5.Cu" signal "GND2")
		(14 "In6.Cu" signal "IN3")
		(16 "In7.Cu" signal "GND3")
		(18 "In8.Cu" signal "VCC")
		(20 "In9.Cu" signal "VCC1")
		(22 "In10.Cu" signal "GND4")
		(24 "In11.Cu" signal "IN4")
		(26 "In12.Cu" signal "GND5")
		(28 "In13.Cu" signal "IN5")
		(30 "In14.Cu" signal "GND6")
		(32 "In15.Cu" signal "IN6")
		(34 "In16.Cu" signal "GND7")
		(2 "B.Cu" signal "BOTTOM")
		(9 "F.Adhes" user "F.Adhesive")
		(11 "B.Adhes" user "B.Adhesive")
		(13 "F.Paste" user "Package Geometry/Pastemask Top")
		(15 "B.Paste" user "Package Geometry/Pastemask Bottom")
		(5 "F.SilkS" user "Ref Des/Silkscreen Top")
		(7 "B.SilkS" user "Ref Des/Silkscreen Bottom")
		(1 "F.Mask" user "Board Geometry/Soldermask Top")
		(3 "B.Mask" user "Board Geometry/Soldermask Bottom")
		(17 "Dwgs.User" user "User.Drawings")
		(19 "Cmts.User" user "User.Comments")
		(21 "Eco1.User" user "User.Eco1")
		(23 "Eco2.User" user "User.Eco2")
		(25 "Edge.Cuts" user "Board Geometry/Outline")
		(27 "Margin" user)
		(31 "F.CrtYd" user "Package Geometry/Place Bound Top")
		(29 "B.CrtYd" user "Package Geometry/Place Bound Bottom")
		(35 "F.Fab" user "Ref Des/Assembly Top")
		(33 "B.Fab" user "Ref Des/Assembly Bottom")
	)
	(footprint ""
		(layer "F.Cu")
		(at 256.466594 -394.17117)
		(property "Reference" "PR2528"
			(at 0 0 0)
			(layer "F.SilkS")
			(hide yes)
			(effects
				(font
					(size 1.27 1.27)
				)
			)
		)
		(property "Value" ""
			(at 0 0 0)
			(layer "F.Fab")
			(effects
				(font
					(size 1.27 1.27)
				)
			)
		)
		(duplicate_pad_numbers_are_jumpers no)
		(fp_line
			(start -0.7874 -0.4064)
			(end 0.7874 -0.4064)
			(stroke
				(width 0.1524)
				(type default)
			)
			(layer "F.SilkS")
		)
		(fp_line
			(start -0.7874 0.4064)
			(end -0.7874 -0.4064)
			(stroke
				(width 0.1524)
				(type default)
			)
			(layer "F.SilkS")
		)
		(fp_line
			(start 0.7874 -0.4064)
			(end 0.7874 0.4064)
			(stroke
				(width 0.1524)
				(type default)
			)
			(layer "F.SilkS")
		)
		(fp_line
			(start 0.7874 0.4064)
			(end -0.7874 0.4064)
			(stroke
				(width 0.1524)
				(type default)
			)
			(layer "F.SilkS")
		)
		(fp_line
			(start -0.67945 -0.305054)
			(end -0.12065 -0.305054)
			(stroke
				(width 0.1)
				(type default)
			)
			(layer "F.Fab")
		)
		(fp_line
			(start -0.67945 0.3048)
			(end -0.67945 -0.305054)
			(stroke
				(width 0.1)
				(type default)
			)
			(layer "F.Fab")
		)
		(fp_line
			(start -0.12065 -0.305054)
			(end -0.12065 -0.2794)
			(stroke
				(width 0.1)
				(type default)
			)
			(layer "F.Fab")
		)
		(fp_line
			(start -0.12065 -0.2794)
			(end 0.12065 -0.2794)
			(stroke
				(width 0.1)
				(type default)
			)
			(layer "F.Fab")
		)
		(fp_line
			(start -0.12065 0.2794)
			(end -0.12065 0.3048)
			(stroke
				(width 0.1)
				(type default)
			)
			(layer "F.Fab")
		)
		(fp_line
			(start -0.12065 0.3048)
			(end -0.67945 0.3048)
			(stroke
				(width 0.1)
				(type default)
			)
			(layer "F.Fab")
		)
		(fp_line
			(start 0.120396 0.2794)
			(end -0.12065 0.2794)
			(stroke
				(width 0.1)
				(type default)
			)
			(layer "F.Fab")
		)
		(fp_line
			(start 0.120396 0.3048)
			(end 0.120396 0.2794)
			(stroke
				(width 0.1)
				(type default)
			)
			(layer "F.Fab")
		)
		(fp_line
			(start 0.12065 -0.3048)
			(end 0.67945 -0.3048)
			(stroke
				(width 0.1)
				(type default)
			)
			(layer "F.Fab")
		)
		(fp_line
			(start 0.12065 -0.2794)
			(end 0.12065 -0.3048)
			(stroke
				(width 0.1)
				(type default)
			)
			(layer "F.Fab")
		)
		(fp_line
			(start 0.67945 -0.3048)
			(end 0.67945 0.3048)
			(stroke
				(width 0.1)
				(type default)
			)
			(layer "F.Fab")
		)
		(fp_line
			(start 0.67945 0.3048)
			(end 0.120396 0.3048)
			(stroke
				(width 0.1)
				(type default)
			)
			(layer "F.Fab")
		)
		(pad "1" smd circle
			(at -0.40005 0)
			(size 0 0)
			(layers "F.Cu" "F.Mask" "F.Paste")
			(net "P12V_HSC_GATE_G1")
		)
		(pad "2" smd circle
			(at 0.40005 0)
			(size 0 0)
			(layers "F.Cu" "F.Mask" "F.Paste")
			(net "P12V_HSC_GATE2")
		)
	)
	(footprint ""
		(layer "F.Cu")
		(at 380.335536 -105.483152 90)
		(property "Reference" "R2513"
			(at 0 0 90)
			(layer "F.SilkS")
			(hide yes)
			(effects
				(font
					(size 1.27 1.27)
				)
			)
		)
		(property "Value" ""
			(at 0 0 90)
			(layer "F.Fab")
			(effects
				(font
					(size 1.27 1.27)
				)
			)
		)
		(duplicate_pad_numbers_are_jumpers no)
		(fp_line
			(start 0.7874 -0.4064)
			(end 0.7874 0.4064)
			(stroke
				(width 0.1524)
				(type default)
			)
			(layer "F.SilkS")
		)
		(fp_line
			(start -0.7874 -0.4064)
			(end 0.7874 -0.4064)
			(stroke
				(width 0.1524)
				(type default)
			)
			(layer "F.SilkS")
		)
		(fp_line
			(start 0.7874 0.4064)
			(end -0.7874 0.4064)
			(stroke
				(width 0.1524)
				(type default)
			)
			(layer "F.SilkS")
		)
		(fp_line
			(start -0.7874 0.4064)
			(end -0.7874 -0.4064)
			(stroke
				(width 0.1524)
				(type default)
			)
			(layer "F.SilkS")
		)
		(fp_line
			(start -0.12065 -0.305054)
			(end -0.12065 -0.2794)
			(stroke
				(width 0.1)
				(type default)
			)
			(layer "F.Fab")
		)
		(fp_line
			(start -0.67945 -0.305054)
			(end -0.12065 -0.305054)
			(stroke
				(width 0.1)
				(type default)
			)
			(layer "F.Fab")
		)
		(fp_line
			(start 0.67945 -0.3048)
			(end 0.67945 0.3048)
			(stroke
				(width 0.1)
				(type default)
			)
			(layer "F.Fab")
		)
		(fp_line
			(start 0.12065 -0.3048)
			(end 0.67945 -0.3048)
			(stroke
				(width 0.1)
				(type default)
			)
			(layer "F.Fab")
		)
		(fp_line
			(start 0.12065 -0.2794)
			(end 0.12065 -0.3048)
			(stroke
				(width 0.1)
				(type default)
			)
			(layer "F.Fab")
		)
		(fp_line
			(start -0.12065 -0.2794)
			(end 0.12065 -0.2794)
			(stroke
				(width 0.1)
				(type default)
			)
			(layer "F.Fab")
		)
		(fp_line
			(start 0.120396 0.2794)
			(end -0.12065 0.2794)
			(stroke
				(width 0.1)
				(type default)
			)
			(layer "F.Fab")
		)
		(fp_line
			(start -0.12065 0.2794)
			(end -0.12065 0.3048)
			(stroke
				(width 0.1)
				(type default)
			)
			(layer "F.Fab")
		)
		(fp_line
			(start 0.67945 0.3048)
			(end 0.120396 0.3048)
			(stroke
				(width 0.1)
				(type default)
			)
			(layer "F.Fab")
		)
		(fp_line
			(start 0.120396 0.3048)
			(end 0.120396 0.2794)
			(stroke
				(width 0.1)
				(type default)
			)
			(layer "F.Fab")
		)
		(fp_line
			(start -0.12065 0.3048)
			(end -0.67945 0.3048)
			(stroke
				(width 0.1)
				(type default)
			)
			(layer "F.Fab")
		)
		(fp_line
			(start -0.67945 0.3048)
			(end -0.67945 -0.305054)
			(stroke
				(width 0.1)
				(type default)
			)
			(layer "F.Fab")
		)
		(pad "1" smd circle
			(at -0.40005 0 90)
			(size 0 0)
			(layers "F.Cu" "F.Mask" "F.Paste")
			(net "PD_GTL2014_BMC_JTAG_DIR_2")
		)
		(pad "2" smd circle
			(at 0.40005 0 90)
			(size 0 0)
			(layers "F.Cu" "F.Mask" "F.Paste")
			(net "GND")
		)
	)
	(footprint ""
		(layer "F.Cu")
		(at 180.03393 -363.113066 90)
		(property "Reference" "PC1210"
			(at 0 0 90)
			(layer "F.SilkS")
			(hide yes)
			(effects
				(font
					(size 1.27 1.27)
				)
			)
		)
		(property "Value" ""
			(at 0 0 90)
			(layer "F.Fab")
			(effects
				(font
					(size 1.27 1.27)
				)
			)
		)
		(duplicate_pad_numbers_are_jumpers no)
		(fp_line
			(start -3.400044 1.249934)
			(end 3.400044 1.249934)
			(stroke
				(width 0.1524)
				(type default)
			)
			(layer "F.SilkS")
		)
		(fp_circle
			(center 0 1.249934)
			(end 0 4.649978)
			(stroke
				(width 0.1524)
				(type default)
			)
			(fill no)
			(layer "F.SilkS")
		)
		(fp_poly
			(pts
				(arc
					(start -3.400044 1.249934)
					(mid 0 4.649978)
					(end 3.400044 1.249934)
				)
			)
			(stroke
				(width 0)
				(type default)
			)
			(fill yes)
			(layer "F.SilkS")
		)
		(fp_circle
			(center 0 1.249934)
			(end 0 4.649978)
			(stroke
				(width 0.1)
				(type default)
			)
			(fill no)
			(layer "F.Fab")
		)
		(pad "1" thru_hole rect
			(at 0 0 90)
			(size 1.524 1.524)
			(drill 1.016)
			(layers "*.Cu" "*.Mask")
			(remove_unused_layers no)
			(net "SW_P12V_PVCCFA_EHV_FIVRA_CPU1_R")
			(clearance 0)
			(padstack
				(mode front_inner_back)
				(layer "Inner"
					(shape circle)
					(size 1.524 1.524)
					(clearance 0)
				)
				(layer "B.Cu"
					(shape rect)
					(size 1.524 1.524)
					(clearance 0)
				)
			)
		)
		(pad "2" thru_hole circle
			(at 0 2.500122 90)
			(size 1.524 1.524)
			(drill 1.016)
			(layers "*.Cu" "*.Mask")
			(remove_unused_layers no)
			(net "GND")
			(clearance 0)
		)
	)
)
